# T6G (Grand Teton) — schematic netlist excerpt (pin names and nets, part order shuffled) for the footprints in the layout excerpt that follows; sources: Cadence DE-HDL packaged netlist, KiCad conversion of 04192023_DAF0TMB3IC0_F0TG_MB_C_brd_V02_OCP.brd

R3510  Q_RES  54.9K 1% CHIP  pkg 0402LF  page 127 : A = P3V3_AUX ; B = FM_SMB_1_ALERT_GPU_N
R1408  Q_RES  1K 1% CHIP  pkg 0201LF  page 309 : A = JTAG_TRST_RT_CPU0_P3_N ; B = GND
R412  Q_RES  2.2K 5% CHIP  pkg 0402LF  page 27 : A = CPU0_PROCHOT_N ; B = PVDD18_S5_P0

(kicad_pcb
	(version 20260206)
	(generator "pcbnew")
	(generator_version "10.0")
	(general
		(thickness 1.6)
		(legacy_teardrops no)
	)
	(paper "A4")
	(title_block
		(title "04192023_DAF0TMB3IC0_F0TG_MB_C_brd_V02_OCP.brd")
		(comment 1 "Grand Teton / footprints 1618-1620 of 8354")
	)
	(layers
		(0 "F.Cu" signal "TOP")
		(4 "In1.Cu" signal "GND")
		(6 "In2.Cu" signal "IN1")
		(8 "In3.Cu" signal "GND1")
		(10 "In4.Cu" signal "IN2")
		(12 "In5.Cu" signal "GND2")
		(14 "In6.Cu" signal "IN3")
		(16 "In7.Cu" signal "GND3")
		(18 "In8.Cu" signal "VCC")
		(20 "In9.Cu" signal "VCC1")
		(22 "In10.Cu" signal "GND4")
		(24 "In11.Cu" signal "IN4")
		(26 "In12.Cu" signal "GND5")
		(28 "In13.Cu" signal "IN5")
		(30 "In14.Cu" signal "GND6")
		(32 "In15.Cu" signal "IN6")
		(34 "In16.Cu" signal "GND7")
		(2 "B.Cu" signal "BOTTOM")
		(9 "F.Adhes" user "F.Adhesive")
		(11 "B.Adhes" user "B.Adhesive")
		(13 "F.Paste" user "Package Geometry/Pastemask Top")
		(15 "B.Paste" user "Package Geometry/Pastemask Bottom")
		(5 "F.SilkS" user "Ref Des/Silkscreen Top")
		(7 "B.SilkS" user "Ref Des/Silkscreen Bottom")
		(1 "F.Mask" user "Board Geometry/Soldermask Top")
		(3 "B.Mask" user "Board Geometry/Soldermask Bottom")
		(17 "Dwgs.User" user "User.Drawings")
		(19 "Cmts.User" user "User.Comments")
		(21 "Eco1.User" user "User.Eco1")
		(23 "Eco2.User" user "User.Eco2")
		(25 "Edge.Cuts" user "Board Geometry/Outline")
		(27 "Margin" user)
		(31 "F.CrtYd" user "Package Geometry/Place Bound Top")
		(29 "B.CrtYd" user "Package Geometry/Place Bound Bottom")
		(35 "F.Fab" user "Ref Des/Assembly Top")
		(33 "B.Fab" user "Ref Des/Assembly Bottom")
	)
	(footprint ""
		(layer "F.Cu")
		(at 113.684304 -418.079428 -90)
		(property "Reference" "R3510"
			(at 0 0 270)
			(layer "F.SilkS")
			(hide yes)
			(effects
				(font
					(size 1.27 1.27)
				)
			)
		)
		(property "Value" ""
			(at 0 0 270)
			(layer "F.Fab")
			(effects
				(font
					(size 1.27 1.27)
				)
			)
		)
		(duplicate_pad_numbers_are_jumpers no)
		(fp_line
			(start -0.7874 0.4064)
			(end -0.7874 -0.4064)
			(stroke
				(width 0.1524)
				(type default)
			)
			(layer "F.SilkS")
		)
		(fp_line
			(start 0.7874 0.4064)
			(end -0.7874 0.4064)
			(stroke
				(width 0.1524)
				(type default)
			)
			(layer "F.SilkS")
		)
		(fp_line
			(start -0.7874 -0.4064)
			(end 0.7874 -0.4064)
			(stroke
				(width 0.1524)
				(type default)
			)
			(layer "F.SilkS")
		)
		(fp_line
			(start 0.7874 -0.4064)
			(end 0.7874 0.4064)
			(stroke
				(width 0.1524)
				(type default)
			)
			(layer "F.SilkS")
		)
		(fp_line
			(start -0.67945 0.3048)
			(end -0.67945 -0.305054)
			(stroke
				(width 0.1)
				(type default)
			)
			(layer "F.Fab")
		)
		(fp_line
			(start -0.12065 0.3048)
			(end -0.67945 0.3048)
			(stroke
				(width 0.1)
				(type default)
			)
			(layer "F.Fab")
		)
		(fp_line
			(start 0.120396 0.3048)
			(end 0.120396 0.2794)
			(stroke
				(width 0.1)
				(type default)
			)
			(layer "F.Fab")
		)
		(fp_line
			(start 0.67945 0.3048)
			(end 0.120396 0.3048)
			(stroke
				(width 0.1)
				(type default)
			)
			(layer "F.Fab")
		)
		(fp_line
			(start -0.12065 0.2794)
			(end -0.12065 0.3048)
			(stroke
				(width 0.1)
				(type default)
			)
			(layer "F.Fab")
		)
		(fp_line
			(start 0.120396 0.2794)
			(end -0.12065 0.2794)
			(stroke
				(width 0.1)
				(type default)
			)
			(layer "F.Fab")
		)
		(fp_line
			(start -0.12065 -0.2794)
			(end 0.12065 -0.2794)
			(stroke
				(width 0.1)
				(type default)
			)
			(layer "F.Fab")
		)
		(fp_line
			(start 0.12065 -0.2794)
			(end 0.12065 -0.3048)
			(stroke
				(width 0.1)
				(type default)
			)
			(layer "F.Fab")
		)
		(fp_line
			(start 0.12065 -0.3048)
			(end 0.67945 -0.3048)
			(stroke
				(width 0.1)
				(type default)
			)
			(layer "F.Fab")
		)
		(fp_line
			(start 0.67945 -0.3048)
			(end 0.67945 0.3048)
			(stroke
				(width 0.1)
				(type default)
			)
			(layer "F.Fab")
		)
		(fp_line
			(start -0.67945 -0.305054)
			(end -0.12065 -0.305054)
			(stroke
				(width 0.1)
				(type default)
			)
			(layer "F.Fab")
		)
		(fp_line
			(start -0.12065 -0.305054)
			(end -0.12065 -0.2794)
			(stroke
				(width 0.1)
				(type default)
			)
			(layer "F.Fab")
		)
		(pad "1" smd circle
			(at -0.40005 0 270)
			(size 0 0)
			(layers "F.Cu" "F.Mask" "F.Paste")
			(net "P3V3_AUX")
		)
		(pad "2" smd circle
			(at 0.40005 0 270)
			(size 0 0)
			(layers "F.Cu" "F.Mask" "F.Paste")
			(net "FM_SMB_1_ALERT_GPU_N")
		)
	)
	(footprint ""
		(layer "F.Cu")
		(at 392.797284 -399.12798)
		(property "Reference" "R1408"
			(at 0 0 0)
			(layer "F.SilkS")
			(hide yes)
			(effects
				(font
					(size 1.27 1.27)
				)
			)
		)
		(property "Value" ""
			(at 0 0 0)
			(layer "F.Fab")
			(effects
				(font
					(size 1.27 1.27)
				)
			)
		)
		(duplicate_pad_numbers_are_jumpers no)
		(fp_line
			(start -0.32512 -0.175006)
			(end 0.32512 -0.175006)
			(stroke
				(width 0.1)
				(type default)
			)
			(layer "F.Fab")
		)
		(fp_line
			(start -0.32512 0.175006)
			(end -0.32512 -0.175006)
			(stroke
				(width 0.1)
				(type default)
			)
			(layer "F.Fab")
		)
		(fp_line
			(start 0.32512 -0.175006)
			(end 0.32512 0.175006)
			(stroke
				(width 0.1)
				(type default)
			)
			(layer "F.Fab")
		)
		(fp_line
			(start 0.32512 0.175006)
			(end -0.32512 0.175006)
			(stroke
				(width 0.1)
				(type default)
			)
			(layer "F.Fab")
		)
		(pad "1" smd rect
			(at -0.2667 0)
			(size 0.3048 0.381)
			(layers "F.Cu" "F.Mask" "F.Paste")
			(net "JTAG_TRST_RT_CPU0_P3_N")
		)
		(pad "2" smd rect
			(at 0.2667 0 180)
			(size 0.3048 0.381)
			(layers "F.Cu" "F.Mask" "F.Paste")
			(net "GND")
		)
	)
	(footprint ""
		(layer "F.Cu")
		(at 323.513958 -193.925952 -90)
		(property "Reference" "R412"
			(at 0 0 270)
			(layer "F.SilkS")
			(hide yes)
			(effects
				(font
					(size 1.27 1.27)
				)
			)
		)
		(property "Value" ""
			(at 0 0 270)
			(layer "F.Fab")
			(effects
				(font
					(size 1.27 1.27)
				)
			)
		)
		(duplicate_pad_numbers_are_jumpers no)
		(fp_line
			(start -0.7874 0.4064)
			(end -0.7874 -0.4064)
			(stroke
				(width 0.1524)
				(type default)
			)
			(layer "F.SilkS")
		)
		(fp_line
			(start 0.7874 0.4064)
			(end -0.7874 0.4064)
			(stroke
				(width 0.1524)
				(type default)
			)
			(layer "F.SilkS")
		)
		(fp_line
			(start -0.7874 -0.4064)
			(end 0.7874 -0.4064)
			(stroke
				(width 0.1524)
				(type default)
			)
			(layer "F.SilkS")
		)
		(fp_line
			(start 0.7874 -0.4064)
			(end 0.7874 0.4064)
			(stroke
				(width 0.1524)
				(type default)
			)
			(layer "F.SilkS")
		)
		(fp_line
			(start -0.67945 0.3048)
			(end -0.67945 -0.305054)
			(stroke
				(width 0.1)
				(type default)
			)
			(layer "F.Fab")
		)
		(fp_line
			(start -0.12065 0.3048)
			(end -0.67945 0.3048)
			(stroke
				(width 0.1)
				(type default)
			)
			(layer "F.Fab")
		)
		(fp_line
			(start 0.120396 0.3048)
			(end 0.120396 0.2794)
			(stroke
				(width 0.1)
				(type default)
			)
			(layer "F.Fab")
		)
		(fp_line
			(start 0.67945 0.3048)
			(end 0.120396 0.3048)
			(stroke
				(width 0.1)
				(type default)
			)
			(layer "F.Fab")
		)
		(fp_line
			(start -0.12065 0.2794)
			(end -0.12065 0.3048)
			(stroke
				(width 0.1)
				(type default)
			)
			(layer "F.Fab")
		)
		(fp_line
			(start 0.120396 0.2794)
			(end -0.12065 0.2794)
			(stroke
				(width 0.1)
				(type default)
			)
			(layer "F.Fab")
		)
		(fp_line
			(start -0.12065 -0.2794)
			(end 0.12065 -0.2794)
			(stroke
				(width 0.1)
				(type default)
			)
			(layer "F.Fab")
		)
		(fp_line
			(start 0.12065 -0.2794)
			(end 0.12065 -0.3048)
			(stroke
				(width 0.1)
				(type default)
			)
			(layer "F.Fab")
		)
		(fp_line
			(start 0.12065 -0.3048)
			(end 0.67945 -0.3048)
			(stroke
				(width 0.1)
				(type default)
			)
			(layer "F.Fab")
		)
		(fp_line
			(start 0.67945 -0.3048)
			(end 0.67945 0.3048)
			(stroke
				(width 0.1)
				(type default)
			)
			(layer "F.Fab")
		)
		(fp_line
			(start -0.67945 -0.305054)
			(end -0.12065 -0.305054)
			(stroke
				(width 0.1)
				(type default)
			)
			(layer "F.Fab")
		)
		(fp_line
			(start -0.12065 -0.305054)
			(end -0.12065 -0.2794)
			(stroke
				(width 0.1)
				(type default)
			)
			(layer "F.Fab")
		)
		(pad "1" smd circle
			(at -0.40005 0 270)
			(size 0 0)
			(layers "F.Cu" "F.Mask" "F.Paste")
			(net "CPU0_PROCHOT_N")
		)
		(pad "2" smd circle
			(at 0.40005 0 270)
			(size 0 0)
			(layers "F.Cu" "F.Mask" "F.Paste")
			(net "PVDD18_S5_P0")
		)
	)
)
